(kicad_pcb
	(version 20260206)
	(generator "pcbnew")
	(generator_version "10.0")
	(general
		(thickness 1.6)
		(legacy_teardrops no)
	)
	(paper "A4")
	(title_block
		(title "04192023_DAF0TMB3IC0_F0TG_MB_C_brd_V02_OCP.brd")
		(comment 1 "Grand Teton / footprints 7328-7332 of 8354")
	)
	(layers
		(0 "F.Cu" signal "TOP")
		(4 "In1.Cu" signal "GND")
		(6 "In2.Cu" signal "IN1")
		(8 "In3.Cu" signal "GND1")
		(10 "In4.Cu" signal "IN2")
		(12 "In5.Cu" signal "GND2")
		(14 "In6.Cu" signal "IN3")
		(16 "In7.Cu" signal "GND3")
		(18 "In8.Cu" signal "VCC")
		(20 "In9.Cu" signal "VCC1")
		(22 "In10.Cu" signal "GND4")
		(24 "In11.Cu" signal "IN4")
		(26 "In12.Cu" signal "GND5")
		(28 "In13.Cu" signal "IN5")
		(30 "In14.Cu" signal "GND6")
		(32 "In15.Cu" signal "IN6")
		(34 "In16.Cu" signal "GND7")
		(2 "B.Cu" signal "BOTTOM")
		(9 "F.Adhes" user "F.Adhesive")
		(11 "B.Adhes" user "B.Adhesive")
		(13 "F.Paste" user "Package Geometry/Pastemask Top")
		(15 "B.Paste" user "Package Geometry/Pastemask Bottom")
		(5 "F.SilkS" user "Ref Des/Silkscreen Top")
		(7 "B.SilkS" user "Ref Des/Silkscreen Bottom")
		(1 "F.Mask" user "Board Geometry/Soldermask Top")
		(3 "B.Mask" user "Board Geometry/Soldermask Bottom")
		(17 "Dwgs.User" user "User.Drawings")
		(19 "Cmts.User" user "User.Comments")
		(21 "Eco1.User" user "User.Eco1")
		(23 "Eco2.User" user "User.Eco2")
		(25 "Edge.Cuts" user "Board Geometry/Outline")
		(27 "Margin" user)
		(31 "F.CrtYd" user "Package Geometry/Place Bound Top")
		(29 "B.CrtYd" user "Package Geometry/Place Bound Bottom")
		(35 "F.Fab" user "Ref Des/Assembly Top")
		(33 "B.Fab" user "Ref Des/Assembly Bottom")
	)
	(footprint ""
		(layer "B.Cu")
		(at 380.536958 -208.530952 90)
		(property "Reference" "C208"
			(at 0 0 90)
			(layer "B.SilkS")
			(hide yes)
			(effects
				(font
					(size 1.27 1.27)
				)
				(justify mirror)
			)
		)
		(property "Value" ""
			(at 0 0 90)
			(layer "B.Fab")
			(effects
				(font
					(size 1.27 1.27)
				)
				(justify mirror)
			)
		)
		(duplicate_pad_numbers_are_jumpers no)
		(fp_line
			(start 0.7874 -0.4064)
			(end -0.7874 -0.4064)
			(stroke
				(width 0.1524)
				(type default)
			)
			(layer "B.SilkS")
		)
		(fp_line
			(start -0.7874 -0.4064)
			(end -0.7874 0.4064)
			(stroke
				(width 0.1524)
				(type default)
			)
			(layer "B.SilkS")
		)
		(fp_line
			(start 0.7874 0.4064)
			(end 0.7874 -0.4064)
			(stroke
				(width 0.1524)
				(type default)
			)
			(layer "B.SilkS")
		)
		(fp_line
			(start -0.7874 0.4064)
			(end 0.7874 0.4064)
			(stroke
				(width 0.1524)
				(type default)
			)
			(layer "B.SilkS")
		)
		(fp_line
			(start 0.67945 -0.305054)
			(end 0.12065 -0.305054)
			(stroke
				(width 0.1)
				(type default)
			)
			(layer "B.Fab")
		)
		(fp_line
			(start 0.12065 -0.305054)
			(end 0.12065 -0.2794)
			(stroke
				(width 0.1)
				(type default)
			)
			(layer "B.Fab")
		)
		(fp_line
			(start -0.12065 -0.3048)
			(end -0.67945 -0.3048)
			(stroke
				(width 0.1)
				(type default)
			)
			(layer "B.Fab")
		)
		(fp_line
			(start -0.67945 -0.3048)
			(end -0.67945 0.3048)
			(stroke
				(width 0.1)
				(type default)
			)
			(layer "B.Fab")
		)
		(fp_line
			(start 0.12065 -0.2794)
			(end -0.12065 -0.2794)
			(stroke
				(width 0.1)
				(type default)
			)
			(layer "B.Fab")
		)
		(fp_line
			(start -0.12065 -0.2794)
			(end -0.12065 -0.3048)
			(stroke
				(width 0.1)
				(type default)
			)
			(layer "B.Fab")
		)
		(fp_line
			(start 0.12065 0.2794)
			(end 0.12065 0.3048)
			(stroke
				(width 0.1)
				(type default)
			)
			(layer "B.Fab")
		)
		(fp_line
			(start -0.120396 0.2794)
			(end 0.12065 0.2794)
			(stroke
				(width 0.1)
				(type default)
			)
			(layer "B.Fab")
		)
		(fp_line
			(start 0.67945 0.3048)
			(end 0.67945 -0.305054)
			(stroke
				(width 0.1)
				(type default)
			)
			(layer "B.Fab")
		)
		(fp_line
			(start 0.12065 0.3048)
			(end 0.67945 0.3048)
			(stroke
				(width 0.1)
				(type default)
			)
			(layer "B.Fab")
		)
		(fp_line
			(start -0.120396 0.3048)
			(end -0.120396 0.2794)
			(stroke
				(width 0.1)
				(type default)
			)
			(layer "B.Fab")
		)
		(fp_line
			(start -0.67945 0.3048)
			(end -0.120396 0.3048)
			(stroke
				(width 0.1)
				(type default)
			)
			(layer "B.Fab")
		)
		(pad "1" smd circle
			(at 0.40005 0 270)
			(size 0 0)
			(layers "B.Cu" "B.Mask" "B.Paste")
			(net "JTAG_CPU0_TDI")
		)
		(pad "2" smd circle
			(at -0.40005 0 270)
			(size 0 0)
			(layers "B.Cu" "B.Mask" "B.Paste")
			(net "GND")
		)
	)
	(footprint ""
		(layer "B.Cu")
		(at 175.836834 -343.785952 -90)
		(property "Reference" "PC802"
			(at 7.354316 -3.474466 270)
			(unlocked yes)
			(layer "B.SilkS")
			(effects
				(font
					(size 0.7874 0.5842)
					(thickness 0.1524)
				)
				(justify left mirror)
			)
		)
		(property "Value" ""
			(at 0 0 90)
			(layer "B.Fab")
			(effects
				(font
					(size 1.27 1.27)
				)
				(justify mirror)
			)
		)
		(duplicate_pad_numbers_are_jumpers no)
		(fp_line
			(start -4.533392 2.249932)
			(end 4.533392 2.249932)
			(stroke
				(width 0.1524)
				(type default)
			)
			(layer "B.SilkS")
		)
		(fp_line
			(start 4.533392 2.249932)
			(end 4.533392 -2.249932)
			(stroke
				(width 0.1524)
				(type default)
			)
			(layer "B.SilkS")
		)
		(fp_line
			(start -4.533392 -2.249932)
			(end -4.533392 2.249932)
			(stroke
				(width 0.1524)
				(type default)
			)
			(layer "B.SilkS")
		)
		(fp_line
			(start 4.533392 -2.249932)
			(end -4.533392 -2.249932)
			(stroke
				(width 0.1524)
				(type default)
			)
			(layer "B.SilkS")
		)
		(fp_rect
			(start 5.39242 2.326132)
			(end 4.533392 -2.326132)
			(stroke
				(width 0)
				(type default)
			)
			(fill yes)
			(layer "B.SilkS")
		)
		(fp_line
			(start -3.750056 2.249932)
			(end 3.750056 2.249932)
			(stroke
				(width 0.1)
				(type default)
			)
			(layer "B.Fab")
		)
		(fp_line
			(start 3.750056 2.249932)
			(end 3.750056 -2.249932)
			(stroke
				(width 0.1)
				(type default)
			)
			(layer "B.Fab")
		)
		(fp_line
			(start -3.750056 -2.249932)
			(end -3.750056 2.249932)
			(stroke
				(width 0.1)
				(type default)
			)
			(layer "B.Fab")
		)
		(fp_line
			(start 3.750056 -2.249932)
			(end -3.750056 -2.249932)
			(stroke
				(width 0.1)
				(type default)
			)
			(layer "B.Fab")
		)
		(fp_text user "+"
			(at 6.322314 0.786384 180)
			(unlocked yes)
			(layer "B.SilkS")
			(effects
				(font
					(size 1.905 1.4224)
					(thickness 0.1524)
				)
				(justify left mirror)
			)
		)
		(fp_text user "-"
			(at -4.8514 -0.14605 270)
			(unlocked yes)
			(layer "B.SilkS")
			(effects
				(font
					(size 1.905 1.4224)
					(thickness 0.1524)
				)
				(justify left mirror)
			)
		)
		(fp_text user "+"
			(at 6.322314 0.786384 180)
			(unlocked yes)
			(layer "B.Fab")
			(effects
				(font
					(size 1.905 1.4224)
					(thickness 0.1524)
				)
				(justify left mirror)
			)
		)
		(fp_text user "-"
			(at -4.8514 -0.14605 270)
			(unlocked yes)
			(layer "B.Fab")
			(effects
				(font
					(size 1.905 1.4224)
					(thickness 0.1524)
				)
				(justify left mirror)
			)
		)
		(pad "1" smd rect
			(at 3.199892 0 90)
			(size 2.413 2.8194)
			(layers "B.Cu" "B.Mask" "B.Paste")
			(net "PVDD11_S3_P1")
		)
		(pad "2" smd rect
			(at -3.199892 0 90)
			(size 2.413 2.8194)
			(layers "B.Cu" "B.Mask" "B.Paste")
			(net "GND")
		)
	)
	(footprint ""
		(layer "B.Cu")
		(at 360.367072 -261.747762 90)
		(property "Reference" "C2636"
			(at 0 0 90)
			(layer "B.SilkS")
			(hide yes)
			(effects
				(font
					(size 1.27 1.27)
				)
				(justify mirror)
			)
		)
		(property "Value" ""
			(at 0 0 90)
			(layer "B.Fab")
			(effects
				(font
					(size 1.27 1.27)
				)
				(justify mirror)
			)
		)
		(duplicate_pad_numbers_are_jumpers no)
		(fp_line
			(start 0.7874 -0.4064)
			(end -0.7874 -0.4064)
			(stroke
				(width 0.1524)
				(type default)
			)
			(layer "B.SilkS")
		)
		(fp_line
			(start -0.7874 -0.4064)
			(end -0.7874 0.4064)
			(stroke
				(width 0.1524)
				(type default)
			)
			(layer "B.SilkS")
		)
		(fp_line
			(start 0.7874 0.4064)
			(end 0.7874 -0.4064)
			(stroke
				(width 0.1524)
				(type default)
			)
			(layer "B.SilkS")
		)
		(fp_line
			(start -0.7874 0.4064)
			(end 0.7874 0.4064)
			(stroke
				(width 0.1524)
				(type default)
			)
			(layer "B.SilkS")
		)
		(fp_line
			(start 0.67945 -0.305054)
			(end 0.12065 -0.305054)
			(stroke
				(width 0.1)
				(type default)
			)
			(layer "B.Fab")
		)
		(fp_line
			(start 0.12065 -0.305054)
			(end 0.12065 -0.2794)
			(stroke
				(width 0.1)
				(type default)
			)
			(layer "B.Fab")
		)
		(fp_line
			(start -0.12065 -0.3048)
			(end -0.67945 -0.3048)
			(stroke
				(width 0.1)
				(type default)
			)
			(layer "B.Fab")
		)
		(fp_line
			(start -0.67945 -0.3048)
			(end -0.67945 0.3048)
			(stroke
				(width 0.1)
				(type default)
			)
			(layer "B.Fab")
		)
		(fp_line
			(start 0.12065 -0.2794)
			(end -0.12065 -0.2794)
			(stroke
				(width 0.1)
				(type default)
			)
			(layer "B.Fab")
		)
		(fp_line
			(start -0.12065 -0.2794)
			(end -0.12065 -0.3048)
			(stroke
				(width 0.1)
				(type default)
			)
			(layer "B.Fab")
		)
		(fp_line
			(start 0.12065 0.2794)
			(end 0.12065 0.3048)
			(stroke
				(width 0.1)
				(type default)
			)
			(layer "B.Fab")
		)
		(fp_line
			(start -0.120396 0.2794)
			(end 0.12065 0.2794)
			(stroke
				(width 0.1)
				(type default)
			)
			(layer "B.Fab")
		)
		(fp_line
			(start 0.67945 0.3048)
			(end 0.67945 -0.305054)
			(stroke
				(width 0.1)
				(type default)
			)
			(layer "B.Fab")
		)
		(fp_line
			(start 0.12065 0.3048)
			(end 0.67945 0.3048)
			(stroke
				(width 0.1)
				(type default)
			)
			(layer "B.Fab")
		)
		(fp_line
			(start -0.120396 0.3048)
			(end -0.120396 0.2794)
			(stroke
				(width 0.1)
				(type default)
			)
			(layer "B.Fab")
		)
		(fp_line
			(start -0.67945 0.3048)
			(end -0.120396 0.3048)
			(stroke
				(width 0.1)
				(type default)
			)
			(layer "B.Fab")
		)
		(pad "1" smd circle
			(at 0.40005 0 270)
			(size 0 0)
			(layers "B.Cu" "B.Mask" "B.Paste")
			(net "PVDD11_S3_P0")
		)
		(pad "2" smd circle
			(at -0.40005 0 270)
			(size 0 0)
			(layers "B.Cu" "B.Mask" "B.Paste")
			(net "GND")
		)
	)
	(footprint ""
		(layer "B.Cu")
		(at 373.329454 -257.930142)
		(property "Reference" "C2583"
			(at 0 0 0)
			(layer "B.SilkS")
			(hide yes)
			(effects
				(font
					(size 1.27 1.27)
				)
				(justify mirror)
			)
		)
		(property "Value" ""
			(at 0 0 0)
			(layer "B.Fab")
			(effects
				(font
					(size 1.27 1.27)
				)
				(justify mirror)
			)
		)
		(duplicate_pad_numbers_are_jumpers no)
		(fp_line
			(start -0.7874 -0.4064)
			(end -0.7874 0.4064)
			(stroke
				(width 0.1524)
				(type default)
			)
			(layer "B.SilkS")
		)
		(fp_line
			(start -0.7874 0.4064)
			(end 0.7874 0.4064)
			(stroke
				(width 0.1524)
				(type default)
			)
			(layer "B.SilkS")
		)
		(fp_line
			(start 0.7874 -0.4064)
			(end -0.7874 -0.4064)
			(stroke
				(width 0.1524)
				(type default)
			)
			(layer "B.SilkS")
		)
		(fp_line
			(start 0.7874 0.4064)
			(end 0.7874 -0.4064)
			(stroke
				(width 0.1524)
				(type default)
			)
			(layer "B.SilkS")
		)
		(fp_line
			(start -0.67945 -0.3048)
			(end -0.67945 0.3048)
			(stroke
				(width 0.1)
				(type default)
			)
			(layer "B.Fab")
		)
		(fp_line
			(start -0.67945 0.3048)
			(end -0.120396 0.3048)
			(stroke
				(width 0.1)
				(type default)
			)
			(layer "B.Fab")
		)
		(fp_line
			(start -0.12065 -0.3048)
			(end -0.67945 -0.3048)
			(stroke
				(width 0.1)
				(type default)
			)
			(layer "B.Fab")
		)
		(fp_line
			(start -0.12065 -0.2794)
			(end -0.12065 -0.3048)
			(stroke
				(width 0.1)
				(type default)
			)
			(layer "B.Fab")
		)
		(fp_line
			(start -0.120396 0.2794)
			(end 0.12065 0.2794)
			(stroke
				(width 0.1)
				(type default)
			)
			(layer "B.Fab")
		)
		(fp_line
			(start -0.120396 0.3048)
			(end -0.120396 0.2794)
			(stroke
				(width 0.1)
				(type default)
			)
			(layer "B.Fab")
		)
		(fp_line
			(start 0.12065 -0.305054)
			(end 0.12065 -0.2794)
			(stroke
				(width 0.1)
				(type default)
			)
			(layer "B.Fab")
		)
		(fp_line
			(start 0.12065 -0.2794)
			(end -0.12065 -0.2794)
			(stroke
				(width 0.1)
				(type default)
			)
			(layer "B.Fab")
		)
		(fp_line
			(start 0.12065 0.2794)
			(end 0.12065 0.3048)
			(stroke
				(width 0.1)
				(type default)
			)
			(layer "B.Fab")
		)
		(fp_line
			(start 0.12065 0.3048)
			(end 0.67945 0.3048)
			(stroke
				(width 0.1)
				(type default)
			)
			(layer "B.Fab")
		)
		(fp_line
			(start 0.67945 -0.305054)
			(end 0.12065 -0.305054)
			(stroke
				(width 0.1)
				(type default)
			)
			(layer "B.Fab")
		)
		(fp_line
			(start 0.67945 0.3048)
			(end 0.67945 -0.305054)
			(stroke
				(width 0.1)
				(type default)
			)
			(layer "B.Fab")
		)
		(pad "1" smd circle
			(at 0.40005 0 180)
			(size 0 0)
			(layers "B.Cu" "B.Mask" "B.Paste")
			(net "PVDDCR_SOC_P0")
		)
		(pad "2" smd circle
			(at -0.40005 0 180)
			(size 0 0)
			(layers "B.Cu" "B.Mask" "B.Paste")
			(net "GND")
		)
	)
	(footprint ""
		(layer "B.Cu")
		(at 500.851424 -457.29398 -90)
		(property "Reference" "X9027"
			(at 4.7244 -1.61163 270)
			(unlocked yes)
			(layer "B.SilkS")
			(effects
				(font
					(size 0.7874 0.5842)
					(thickness 0.1524)
				)
				(justify left mirror)
			)
		)
		(property "Value" ""
			(at 0 0 90)
			(layer "B.Fab")
			(effects
				(font
					(size 1.27 1.27)
				)
				(justify mirror)
			)
		)
		(property "User Part Number" "N_A"
			(at -1.30175 1.27 180)
			(unlocked yes)
			(layer "Cmts.User")
			(hide yes)
			(effects
				(font
					(size 0.635 0.4064)
					(thickness 0.1524)
				)
				(justify mirror)
			)
		)
		(property "Device Type" "TP_TDR_4P_FTS_TH-TP_TDR_4P_DIP,EMPTY,TP15"
			(at -1.30175 1.27 180)
			(unlocked yes)
			(layer "B.Fab")
			(hide yes)
			(effects
				(font
					(size 0.635 0.4064)
					(thickness 0.1524)
				)
				(justify mirror)
			)
		)
		(duplicate_pad_numbers_are_jumpers no)
		(fp_line
			(start -2.54 3.81)
			(end -2.54 3.6703)
			(stroke
				(width 0.1524)
				(type default)
			)
			(layer "B.SilkS")
		)
		(fp_line
			(start 0 3.81)
			(end -2.54 3.81)
			(stroke
				(width 0.1524)
				(type default)
			)
			(layer "B.SilkS")
		)
		(fp_line
			(start 0 3.175)
			(end 0 3.81)
			(stroke
				(width 0.1524)
				(type default)
			)
			(layer "B.SilkS")
		)
		(fp_line
			(start -2.54 1.4097)
			(end -2.54 1.1303)
			(stroke
				(width 0.1524)
				(type default)
			)
			(layer "B.SilkS")
		)
		(fp_line
			(start 0 0.635)
			(end 0 1.905)
			(stroke
				(width 0.1524)
				(type default)
			)
			(layer "B.SilkS")
		)
		(fp_line
			(start -2.54 -1.1303)
			(end -2.54 -1.27)
			(stroke
				(width 0.1524)
				(type default)
			)
			(layer "B.SilkS")
		)
		(fp_line
			(start -2.54 -1.27)
			(end 0 -1.27)
			(stroke
				(width 0.1524)
				(type default)
			)
			(layer "B.SilkS")
		)
		(fp_line
			(start 0 -1.27)
			(end 0 -0.635)
			(stroke
				(width 0.1524)
				(type default)
			)
			(layer "B.SilkS")
		)
		(fp_poly
			(pts
				(xy 0.761746 0) (xy 2.285746 -0.762) (xy 2.285746 0.762)
			)
			(stroke
				(width 0)
				(type default)
			)
			(fill yes)
			(layer "B.SilkS")
		)
		(fp_line
			(start -2.54 3.81)
			(end -2.54 -1.27)
			(stroke
				(width 0.1)
				(type default)
			)
			(layer "B.Fab")
		)
		(fp_line
			(start 0 3.81)
			(end -2.54 3.81)
			(stroke
				(width 0.1)
				(type default)
			)
			(layer "B.Fab")
		)
		(fp_line
			(start -2.54 -1.27)
			(end 0 -1.27)
			(stroke
				(width 0.1)
				(type default)
			)
			(layer "B.Fab")
		)
		(fp_line
			(start 0 -1.27)
			(end 0 3.81)
			(stroke
				(width 0.1)
				(type default)
			)
			(layer "B.Fab")
		)
		(fp_poly
			(pts
				(xy 0.761746 0) (xy 2.285746 -0.762) (xy 2.285746 0.762)
			)
			(stroke
				(width 0)
				(type default)
			)
			(fill yes)
			(layer "B.Fab")
		)
		(pad "1" thru_hole circle
			(at 0 0 90)
			(size 1.0033 1.0033)
			(drill 0.249936)
			(layers "*.Cu" "*.Mask")
			(remove_unused_layers no)
			(net "TDR_DIFF_85_NECK_IN5_DN")
			(clearance 0.10795)
			(padstack
				(mode front_inner_back)
				(layer "Inner"
					(shape circle)
					(size 0.8001 0.8001)
					(clearance 0.1524)
				)
				(layer "B.Cu"
					(shape circle)
					(size 1.0033 1.0033)
					(thermal_gap 0.10795)
					(clearance 0.10795)
				)
			)
		)
		(pad "2" thru_hole circle
			(at -2.54 0 90)
			(size 1.9939 1.9939)
			(drill 0.249936)
			(layers "*.Cu" "*.Mask")
			(remove_unused_layers no)
			(net "T1_GND")
			(clearance 0.10795)
			(padstack
				(mode front_inner_back)
				(layer "Inner"
					(shape circle)
					(size 0.8001 0.8001)
					(clearance 0.1524)
				)
				(layer "B.Cu"
					(shape circle)
					(size 1.9939 1.9939)
					(thermal_gap 0.10795)
					(clearance 0.10795)
				)
			)
		)
		(pad "3" thru_hole circle
			(at -2.54 2.54 90)
			(size 1.9939 1.9939)
			(drill 0.249936)
			(layers "*.Cu" "*.Mask")
			(remove_unused_layers no)
			(net "T1_GND")
			(clearance 0.10795)
			(padstack
				(mode front_inner_back)
				(layer "Inner"
					(shape circle)
					(size 0.8001 0.8001)
					(clearance 0.1524)
				)
				(layer "B.Cu"
					(shape circle)
					(size 1.9939 1.9939)
					(thermal_gap 0.10795)
					(clearance 0.10795)
				)
			)
		)
		(pad "4" thru_hole circle
			(at 0 2.54 90)
			(size 1.0033 1.0033)
			(drill 0.249936)
			(layers "*.Cu" "*.Mask")
			(remove_unused_layers no)
			(net "TDR_DIFF_85_NECK_IN5_DP")
			(clearance 0.10795)
			(padstack
				(mode front_inner_back)
				(layer "Inner"
					(shape circle)
					(size 0.8001 0.8001)
					(clearance 0.1524)
				)
				(layer "B.Cu"
					(shape circle)
					(size 1.0033 1.0033)
					(thermal_gap 0.10795)
					(clearance 0.10795)
				)
			)
		)
	)
)
